FILE_TYPE = CONNECTIVITY;
{Allegro Design Entry HDL 16.6-p007 (v16-6-112F) 10/10/2012}
"PAGE_NUMBER" = 88;
0"NC";
1"M_M_BA<1:0>";
2"M_M_CS_N<7:0>";
3"M_M_MA<17:0>";
4"M_M_ECC<7:0>";
5"M_M_CKE<3:0>";
6"M_M_BG<1:0>";
7"M_M_ODT<3:0>";
8"M_M_CLK_DP<3:0>";
9"M_M_CLK_DN<3:0>";
10"M_M_DQ<63:0>";
11"M_M_DQS_DP<17:0>";
12"M_M_DQS_DN<17:0>";
13"PVDDQ_KLM\g";
14"GND\g";
15"GND\g";
16"GND\g";
17"PVPP_KLM\g";
18"PVPP_KLM\g";
19"P12V_NVDIMM_KLM\g";
20"GND\g";
21"PVTT_KLM\g";
22"M_M_DQS_DN<1>";
23"M_M_DQS_DP<0>";
24"M_M_DQS_DN<0>";
25"M_M_DQ<55>";
26"M_M_DQ<56>";
27"M_M_ALERT_N";
28"M_M_DQ<45>";
29"M_M_MA<14>";
30"M_M_DQ<54>";
31"M_M_DQ<53>";
32"M_M_DQS_DP<17>";
33"M_M_DQS_DP<9>";
34"M_M_DQS_DN<9>";
35"M_M_DQS_DP<8>";
36"M_M_DQS_DN<8>";
37"M_M_DQS_DP<7>";
38"M_M_DQS_DN<7>";
39"M_M_DQS_DN<17>";
40"M_M_DQS_DP<16>";
41"M_M_DQS_DN<16>";
42"M_M_DQS_DP<15>";
43"M_M_DQS_DN<15>";
44"M_M_DQS_DP<14>";
45"M_M_DQS_DN<14>";
46"M_M_DQS_DP<13>";
47"M_M_DQS_DN<13>";
48"M_M_DQS_DP<12>";
49"M_M_DQS_DN<12>";
50"M_M_DQS_DP<11>";
51"M_M_DQS_DN<11>";
52"M_M_DQS_DP<10>";
53"M_M_DQS_DN<10>";
54"M_M_DQS_DP<6>";
55"M_M_DQS_DN<6>";
56"M_M_DQS_DP<5>";
57"M_M_DQS_DN<5>";
58"M_M_DQS_DP<4>";
59"M_M_DQS_DN<4>";
60"M_M_DQS_DP<3>";
61"M_M_DQS_DN<3>";
62"M_M_DQS_DP<2>";
63"M_M_DQS_DN<2>";
64"M_M_DQS_DP<1>";
65"M_M_DQ<63>";
66"M_M_DQ<61>";
67"M_M_DQ<62>";
68"M_M_DQ<60>";
69"M_M_DQ<58>";
70"M_M_DQ<57>";
71"M_M_DQ<50>";
72"M_M_DQ<51>";
73"M_M_DQ<52>";
74"M_M_DQ<59>";
75"M_M_MA<4>";
76"M_M_MA<16>";
77"M_M_MA<15>";
78"M_M_MA<11>";
79"M_M_MA<10>";
80"M_M_MA<9>";
81"M_M_MA<8>";
82"M_M_MA<7>";
83"M_M_MA<6>";
84"M_M_MA<5>";
85"M_M_MA<17>";
86"M_M_MA<13>";
87"M_M_MA<12>";
88"M_M_DQ<47>";
89"M_M_DQ<48>";
90"M_M_DQ<49>";
91"M_M_DQ<40>";
92"M_M_DQ<41>";
93"M_M_DQ<42>";
94"M_M_DQ<43>";
95"M_M_DQ<44>";
96"M_M_DQ<46>";
97"M_M_DQ<30>";
98"M_M_DQ<38>";
99"M_M_DQ<36>";
100"M_M_DQ<35>";
101"M_M_DQ<31>";
102"M_M_DQ<32>";
103"M_M_DQ<33>";
104"M_M_DQ<34>";
105"M_M_DQ<37>";
106"M_M_DQ<39>";
107"M_M_DQ<22>";
108"M_M_DQ<26>";
109"M_M_DQ<27>";
110"M_M_DQ<20>";
111"M_M_DQ<21>";
112"M_M_DQ<23>";
113"M_M_DQ<24>";
114"M_M_DQ<25>";
115"M_M_DQ<28>";
116"M_M_DQ<29>";
117"M_M_DQ<16>";
118"M_M_DQ<15>";
119"M_M_DQ<14>";
120"M_M_DQ<12>";
121"M_M_DQ<11>";
122"M_M_DQ<10>";
123"M_M_DQ<17>";
124"M_M_DQ<9>";
125"M_M_DQ<13>";
126"M_M_DQ<18>";
127"M_M_DQ<19>";
128"M_M_DQ<8>";
129"M_M_DQ<5>";
130"M_M_DQ<4>";
131"M_M_DQ<3>";
132"M_M_DQ<2>";
133"M_M_DQ<0>";
134"M_M_DQ<1>";
135"M_M_DQ<6>";
136"M_M_DQ<7>";
137"M_M_ACT_N";
138"M_M_CLK_DN<2>";
139"M_M_CLK_DN<3>";
140"M_M_CLK_DP<3>";
141"M_M_CLK_DP<2>";
142"M_M_MA<1>";
143"M_M_CS_N<4>";
144"M_M_CKE<2>";
145"M_M_ODT<3>";
146"M_M_ODT<2>";
147"M_M_ECC<7>";
148"M_M_MA<2>";
149"M_M_BA<0>";
150"M_M_BG<1>";
151"M_M_BG<0>";
152"M_M_CKE<3>";
153"M_M_ECC<0>";
154"M_M_ECC<1>";
155"M_M_ECC<2>";
156"M_M_ECC<3>";
157"M_M_ECC<4>";
158"M_M_ECC<5>";
159"M_M_ECC<6>";
160"M_M_MA<3>";
161"M_M_MA<0>";
162"M_M_CS_N<5>";
163"M_M_CS_N<6>";
164"M_M_CS_N<7>";
165"M_M_BA<1>";
166"M_M_C<2>";
167"M_KLM_RST_N";
168"M_M_PAR";
169"FM_DIMM_EVENT_COD_N";
170"FM_ADR_COMPLETE_KLM_N";
171"SMB_DDR_KLM_VPP_SDA";
172"SMB_DDR_KLM_VPP_SCL";
173"TP_CH_M_DIMM_M1_RFU_1";
174"TP_CH_M_DIMM_M1_RFU_0";
175"TP_CH_M_DIMM_M1_RFU_2";
176"M_M_VREF";
%"TAP"
"6","(-1700,2050)","2","mstr_standard","I100";
;
CDS_LIB"mstr_standard"
BODY_TYPE"PLUMBING"
HDL_TAP"TRUE";
"B \NAC \NWC"10;
"S \NAC"
BN"9"124;
%"TAP"
"6","(-1700,2150)","2","mstr_standard","I101";
;
CDS_LIB"mstr_standard"
BODY_TYPE"PLUMBING"
HDL_TAP"TRUE";
"B \NAC \NWC"10;
"S \NAC"
BN"11"121;
%"TAP"
"6","(-1700,2200)","2","mstr_standard","I102";
;
CDS_LIB"mstr_standard"
BODY_TYPE"PLUMBING"
HDL_TAP"TRUE";
"B \NAC \NWC"10;
"S \NAC"
BN"12"120;
%"TAP"
"6","(-1700,1950)","2","mstr_standard","I103";
;
CDS_LIB"mstr_standard"
BODY_TYPE"PLUMBING"
HDL_TAP"TRUE";
"B \NAC \NWC"10;
"S \NAC"
BN"7"136;
%"TAP"
"6","(-1700,1900)","2","mstr_standard","I104";
;
CDS_LIB"mstr_standard"
BODY_TYPE"PLUMBING"
HDL_TAP"TRUE";
"B \NAC \NWC"10;
"S \NAC"
BN"6"135;
%"TAP"
"6","(-1700,1850)","2","mstr_standard","I105";
;
CDS_LIB"mstr_standard"
BODY_TYPE"PLUMBING"
HDL_TAP"TRUE";
"B \NAC \NWC"10;
"S \NAC"
BN"5"129;
%"TAP"
"6","(-1700,1800)","2","mstr_standard","I106";
;
CDS_LIB"mstr_standard"
BODY_TYPE"PLUMBING"
HDL_TAP"TRUE";
"B \NAC \NWC"10;
"S \NAC"
BN"4"130;
%"TAP"
"6","(-1700,1750)","2","mstr_standard","I107";
;
CDS_LIB"mstr_standard"
BODY_TYPE"PLUMBING"
HDL_TAP"TRUE";
"B \NAC \NWC"10;
"S \NAC"
BN"3"131;
%"TAP"
"6","(-1700,1600)","2","mstr_standard","I108";
;
CDS_LIB"mstr_standard"
BODY_TYPE"PLUMBING"
HDL_TAP"TRUE";
"B \NAC \NWC"10;
"S \NAC"
BN"0"133;
%"TAP"
"6","(-1700,1700)","2","mstr_standard","I109";
;
CDS_LIB"mstr_standard"
BODY_TYPE"PLUMBING"
HDL_TAP"TRUE";
"B \NAC \NWC"10;
"S \NAC"
BN"2"132;
%"PVDDQ_KLM"
"1","(-1350,2550)","0","mstr_symbols","I11";
;
VOLTAGE"1.2V"
BOM_COST"PROC"
CDS_LIB"mstr_symbols"
BODY_TYPE"PLUMBING"
ROOM"PROC"
HDL_POWER"PVDDQ_KLM";
"G\NAC"13;
%"TAP"
"6","(-1700,1650)","2","mstr_standard","I110";
;
CDS_LIB"mstr_standard"
BODY_TYPE"PLUMBING"
HDL_TAP"TRUE";
"B \NAC \NWC"10;
"S \NAC"
BN"1"134;
%"SCONN288_H44441003"
"1","(-2450,3100)","0","mstr_sconn","I111";
;
CDS_SEC"1"
LOCATION"J9L1"
PART_NUMBER"H44441-003"
MATERIAL"SCONN"
BOM_SS"NOPOP"
PACK_TYPE"PIP"
SEC_TYPE"PIP"
CDS_LIB"mstr_sconn"
BOM_COST"DDR4_CH_M"
SEC"1"
CDS_LOCATION"J9L1"
ROOM"DDR4_CH_M";
"DQ<63>"
$PN"280"65;
"BA<1>"
$PN"224"165;
"CK1N"
$PN"219"139;
"CK0P"
$PN"74"141;
"S3_N_C<1>"
$PN"237"164;
"S2_N_C<0>"
$PN"93"163;
"S1_N"
$PN"89"162;
"DQ<29>"
$PN"181"116;
"DQ<28>"
$PN"36"115;
"C<2>"
$PN"235"166;
"A0"
$PN"79"161;
"A1"
$PN"72"142;
"A12"
$PN"65"87;
"A13"
$PN"232"86;
"A17"
$PN"234"85;
"A3"
$PN"71"160;
"A4"
$PN"214"75;
"A5"
$PN"213"84;
"A6"
$PN"69"83;
"A7"
$PN"211"82;
"A8"
$PN"68"81;
"A9"
$PN"66"80;
"CB<6>"
$PN"54"159;
"CB<5>"
$PN"192"158;
"CB<4>"
$PN"47"157;
"CB<3>"
$PN"201"156;
"CB<2>"
$PN"56"155;
"CB<1>"
$PN"194"154;
"CB<0>"
$PN"49"153;
"CK0N"
$PN"75"138;
"CKE<1>"
$PN"203"152;
"DQ<62>"
$PN"135"67;
"DQ<61>"
$PN"273"66;
"DQ<60>"
$PN"128"68;
"DQ<59>"
$PN"282"74;
"DQ<56>"
$PN"130"26;
"DQ<55>"
$PN"269"25;
"DQ<46>"
$PN"113"96;
"DQ<45>"
$PN"251"28;
"DQ<44>"
$PN"106"95;
"DQ<43>"
$PN"260"94;
"DQ<42>"
$PN"115"93;
"DQ<41>"
$PN"253"92;
"DQ<40>"
$PN"108"91;
"DQ<39>"
$PN"247"106;
"DQ<37>"
$PN"240"105;
"DQ<34>"
$PN"104"104;
"DQ<33>"
$PN"242"103;
"DQ<32>"
$PN"97"102;
"DQ<31>"
$PN"188"101;
"DQ<30>"
$PN"43"97;
"DQ<25>"
$PN"183"114;
"DQ<24>"
$PN"38"113;
"DQ<23>"
$PN"177"112;
"DQ<22>"
$PN"32"107;
"DQ<21>"
$PN"170"111;
"DQ<20>"
$PN"25"110;
"DQ<19>"
$PN"179"127;
"DQ<18>"
$PN"34"126;
"DQ<16>"
$PN"27"117;
"DQ<14>"
$PN"21"119;
"DQ<13>"
$PN"159"125;
"DQ<12>"
$PN"14"120;
"DQ<11>"
$PN"168"121;
"DQ<10>"
$PN"23"122;
"DQ<9>"
$PN"161"124;
"DQ<8>"
$PN"16"128;
"DQ<7>"
$PN"155"136;
"DQ<6>"
$PN"10"135;
"EVENT_N"
$PN"78"169;
"PAR"
$PN"222"168;
"RESET_N"
$PN"58"167;
"RFU<2>"
$PN"144"175;
"SCL"
$PN"141"172;
"SDA"
$PN"285"171;
"VREFCA"
$PN"146"176;
"CK1P"
$PN"218"140;
"BG<0>"
$PN"63"151;
"BG<1>"
$PN"207"150;
"BA<0>"
$PN"81"149;
"SA<0>"
$PN"139"17;
"VDDSPD"
$PN"284"17;
"SA<2>"
$PN"238"17;
"SA<1>"
$PN"140"15;
"DQ<1>"
$PN"150"134;
"DQ<0>"
$PN"5"133;
"ACT_N"
$PN"62"137;
"ALERT_N"
$PN"208"27;
"A2"
$PN"216"148;
"DQ<35>"
$PN"249"100;
"DQ<36>"
$PN"95"99;
"DQ<38>"
$PN"102"98;
"A10"
$PN"225"79;
"A11"
$PN"210"78;
"A14_WE_N"
$PN"228"29;
"A15_CAS_N"
$PN"86"77;
"A16_RAS_N"
$PN"82"76;
"CB<7>"
$PN"199"147;
"ODT<0>"
$PN"87"146;
"ODT<1>"
$PN"91"145;
"CKE<0>"
$PN"60"144;
"S0_N"
$PN"84"143;
"DQ<27>"
$PN"190"109;
"DQ<26>"
$PN"45"108;
"DQ<15>"
$PN"166"118;
"DQ<17>"
$PN"172"123;
"RFU<0>"
$PN"205"174;
"RFU<1>"
$PN"227"173;
"SAVE_N_NC"
$PN"230"170;
"DQ<57>"
$PN"275"70;
"DQ<58>"
$PN"137"69;
"DQ<54>"
$PN"124"30;
"DQ<53>"
$PN"262"31;
"DQ<52>"
$PN"117"73;
"DQ<51>"
$PN"271"72;
"DQ<50>"
$PN"126"71;
"DQ<49>"
$PN"264"90;
"DQ<48>"
$PN"119"89;
"DQ<47>"
$PN"258"88;
"DQ<2>"
$PN"12"132;
"DQ<3>"
$PN"157"131;
"DQ<4>"
$PN"3"130;
"DQ<5>"
$PN"148"129;
%"TAP"
"6","(-3200,4700)","0","mstr_standard","I112";
;
CDS_LIB"mstr_standard"
BODY_TYPE"PLUMBING"
HDL_TAP"TRUE";
"B \NAC \NWC"3;
"S \NAC"
BN"16"76;
%"TAP"
"6","(-3200,4750)","0","mstr_standard","I113";
;
CDS_LIB"mstr_standard"
BODY_TYPE"PLUMBING"
HDL_TAP"TRUE";
"B \NAC \NWC"3;
"S \NAC"
BN"17"85;
%"TAP"
"6","(-3200,4650)","0","mstr_standard","I114";
;
CDS_LIB"mstr_standard"
BODY_TYPE"PLUMBING"
HDL_TAP"TRUE";
"B \NAC \NWC"3;
"S \NAC"
BN"15"77;
%"TAP"
"6","(-3200,4600)","0","mstr_standard","I115";
;
CDS_LIB"mstr_standard"
BODY_TYPE"PLUMBING"
HDL_TAP"TRUE";
"B \NAC \NWC"3;
"S \NAC"
BN"14"29;
%"TAP"
"6","(-3200,4550)","0","mstr_standard","I116";
;
CDS_LIB"mstr_standard"
BODY_TYPE"PLUMBING"
HDL_TAP"TRUE";
"B \NAC \NWC"3;
"S \NAC"
BN"13"86;
%"TAP"
"6","(-3200,4500)","0","mstr_standard","I117";
;
CDS_LIB"mstr_standard"
BODY_TYPE"PLUMBING"
HDL_TAP"TRUE";
"B \NAC \NWC"3;
"S \NAC"
BN"12"87;
%"TAP"
"6","(-3200,4450)","0","mstr_standard","I118";
;
CDS_LIB"mstr_standard"
BODY_TYPE"PLUMBING"
HDL_TAP"TRUE";
"B \NAC \NWC"3;
"S \NAC"
BN"11"78;
%"TAP"
"6","(-3200,4400)","0","mstr_standard","I119";
;
CDS_LIB"mstr_standard"
BODY_TYPE"PLUMBING"
HDL_TAP"TRUE";
"B \NAC \NWC"3;
"S \NAC"
BN"10"79;
%"TAP"
"6","(900,4500)","2","mstr_standard","I12";
;
CDS_LIB"mstr_standard"
BODY_TYPE"PLUMBING"
HDL_TAP"TRUE";
"B \NAC \NWC"12;
"S \NAC"
BN"11"51;
%"TAP"
"6","(-3200,4300)","0","mstr_standard","I120";
;
CDS_LIB"mstr_standard"
BODY_TYPE"PLUMBING"
HDL_TAP"TRUE";
"B \NAC \NWC"3;
"S \NAC"
BN"8"81;
%"TAP"
"6","(-3200,4350)","0","mstr_standard","I121";
;
CDS_LIB"mstr_standard"
BODY_TYPE"PLUMBING"
HDL_TAP"TRUE";
"B \NAC \NWC"3;
"S \NAC"
BN"9"80;
%"TAP"
"6","(-3200,4250)","0","mstr_standard","I122";
;
CDS_LIB"mstr_standard"
BODY_TYPE"PLUMBING"
HDL_TAP"TRUE";
"B \NAC \NWC"3;
"S \NAC"
BN"7"82;
%"TAP"
"6","(-3200,4200)","0","mstr_standard","I123";
;
CDS_LIB"mstr_standard"
BODY_TYPE"PLUMBING"
HDL_TAP"TRUE";
"B \NAC \NWC"3;
"S \NAC"
BN"6"83;
%"TAP"
"6","(-3200,4150)","0","mstr_standard","I124";
;
CDS_LIB"mstr_standard"
BODY_TYPE"PLUMBING"
HDL_TAP"TRUE";
"B \NAC \NWC"3;
"S \NAC"
BN"5"84;
%"TAP"
"6","(-3200,4100)","0","mstr_standard","I125";
;
CDS_LIB"mstr_standard"
BODY_TYPE"PLUMBING"
HDL_TAP"TRUE";
"B \NAC \NWC"3;
"S \NAC"
BN"4"75;
%"TAP"
"6","(-3200,4050)","0","mstr_standard","I126";
;
CDS_LIB"mstr_standard"
BODY_TYPE"PLUMBING"
HDL_TAP"TRUE";
"B \NAC \NWC"3;
"S \NAC"
BN"3"160;
%"TAP"
"6","(-3200,4000)","0","mstr_standard","I127";
;
CDS_LIB"mstr_standard"
BODY_TYPE"PLUMBING"
HDL_TAP"TRUE";
"B \NAC \NWC"3;
"S \NAC"
BN"2"148;
%"TAP"
"6","(-3200,3950)","0","mstr_standard","I128";
;
CDS_LIB"mstr_standard"
BODY_TYPE"PLUMBING"
HDL_TAP"TRUE";
"B \NAC \NWC"3;
"S \NAC"
BN"1"142;
%"TAP"
"6","(-3200,3900)","0","mstr_standard","I129";
;
CDS_LIB"mstr_standard"
BODY_TYPE"PLUMBING"
HDL_TAP"TRUE";
"B \NAC \NWC"3;
"S \NAC"
BN"0"161;
%"TAP"
"6","(900,4400)","2","mstr_standard","I13";
;
CDS_LIB"mstr_standard"
BODY_TYPE"PLUMBING"
HDL_TAP"TRUE";
"B \NAC \NWC"12;
"S \NAC"
BN"10"53;
%"TAP"
"6","(-3200,3800)","0","mstr_standard","I130";
;
CDS_LIB"mstr_standard"
BODY_TYPE"PLUMBING"
HDL_TAP"TRUE";
"B \NAC \NWC"1;
"S \NAC"
BN"1"165;
%"TAP"
"6","(-3200,3750)","0","mstr_standard","I133";
;
CDS_LIB"mstr_standard"
BODY_TYPE"PLUMBING"
HDL_TAP"TRUE";
"B \NAC \NWC"1;
"S \NAC"
BN"0"149;
%"TAP"
"6","(-3200,3650)","0","mstr_standard","I134";
;
CDS_LIB"mstr_standard"
BODY_TYPE"PLUMBING"
HDL_TAP"TRUE";
"B \NAC \NWC"6;
"S \NAC"
BN"0"151;
%"TAP"
"6","(-3200,3700)","0","mstr_standard","I135";
;
CDS_LIB"mstr_standard"
BODY_TYPE"PLUMBING"
HDL_TAP"TRUE";
"B \NAC \NWC"6;
"S \NAC"
BN"1"150;
%"TAP"
"6","(-3200,2650)","0","mstr_standard","I138";
;
CDS_LIB"mstr_standard"
BODY_TYPE"PLUMBING"
HDL_TAP"TRUE";
"B \NAC \NWC"4;
"S \NAC"
BN"6"159;
%"TAP"
"6","(-3200,2700)","0","mstr_standard","I139";
;
CDS_LIB"mstr_standard"
BODY_TYPE"PLUMBING"
HDL_TAP"TRUE";
"B \NAC \NWC"4;
"S \NAC"
BN"7"147;
%"TAP"
"6","(900,4300)","2","mstr_standard","I14";
;
CDS_LIB"mstr_standard"
BODY_TYPE"PLUMBING"
HDL_TAP"TRUE";
"B \NAC \NWC"12;
"S \NAC"
BN"9"34;
%"TAP"
"6","(-3200,2600)","0","mstr_standard","I140";
;
CDS_LIB"mstr_standard"
BODY_TYPE"PLUMBING"
HDL_TAP"TRUE";
"B \NAC \NWC"4;
"S \NAC"
BN"5"158;
%"TAP"
"6","(-3200,2550)","0","mstr_standard","I141";
;
CDS_LIB"mstr_standard"
BODY_TYPE"PLUMBING"
HDL_TAP"TRUE";
"B \NAC \NWC"4;
"S \NAC"
BN"4"157;
%"TAP"
"6","(-3200,2500)","0","mstr_standard","I142";
;
CDS_LIB"mstr_standard"
BODY_TYPE"PLUMBING"
HDL_TAP"TRUE";
"B \NAC \NWC"4;
"S \NAC"
BN"3"156;
%"TAP"
"6","(-3200,2450)","0","mstr_standard","I143";
;
CDS_LIB"mstr_standard"
BODY_TYPE"PLUMBING"
HDL_TAP"TRUE";
"B \NAC \NWC"4;
"S \NAC"
BN"2"155;
%"TAP"
"6","(-3200,2400)","0","mstr_standard","I144";
;
CDS_LIB"mstr_standard"
BODY_TYPE"PLUMBING"
HDL_TAP"TRUE";
"B \NAC \NWC"4;
"S \NAC"
BN"1"154;
%"TAP"
"6","(-3200,2350)","0","mstr_standard","I145";
;
CDS_LIB"mstr_standard"
BODY_TYPE"PLUMBING"
HDL_TAP"TRUE";
"B \NAC \NWC"4;
"S \NAC"
BN"0"153;
%"TAP"
"6","(900,4200)","2","mstr_standard","I15";
;
CDS_LIB"mstr_standard"
BODY_TYPE"PLUMBING"
HDL_TAP"TRUE";
"B \NAC \NWC"12;
"S \NAC"
BN"8"36;
%"TAP"
"6","(-3650,3450)","0","mstr_standard","I152";
;
CDS_LIB"mstr_standard"
BODY_TYPE"PLUMBING"
HDL_TAP"TRUE";
"B \NAC \NWC"8;
"S \NAC"
BN"2"141;
%"TAP"
"6","(-3800,3400)","0","mstr_standard","I153";
;
CDS_LIB"mstr_standard"
BODY_TYPE"PLUMBING"
HDL_TAP"TRUE";
"B \NAC \NWC"9;
"S \NAC"
BN"2"138;
%"TAP"
"6","(900,4100)","2","mstr_standard","I16";
;
CDS_LIB"mstr_standard"
BODY_TYPE"PLUMBING"
HDL_TAP"TRUE";
"B \NAC \NWC"12;
"S \NAC"
BN"7"38;
%"TAP"
"6","(-3200,3250)","0","mstr_standard","I160";
;
CDS_LIB"mstr_standard"
BODY_TYPE"PLUMBING"
HDL_TAP"TRUE";
"B \NAC \NWC"2;
"S \NAC"
BN"7"164;
%"TAP"
"6","(-3200,3200)","0","mstr_standard","I161";
;
CDS_LIB"mstr_standard"
BODY_TYPE"PLUMBING"
HDL_TAP"TRUE";
"B \NAC \NWC"2;
"S \NAC"
BN"6"163;
%"TAP"
"6","(-3200,3150)","0","mstr_standard","I162";
;
CDS_LIB"mstr_standard"
BODY_TYPE"PLUMBING"
HDL_TAP"TRUE";
"B \NAC \NWC"2;
"S \NAC"
BN"5"162;
%"TAP"
"6","(-3200,3100)","0","mstr_standard","I163";
;
CDS_LIB"mstr_standard"
BODY_TYPE"PLUMBING"
HDL_TAP"TRUE";
"B \NAC \NWC"2;
"S \NAC"
BN"4"143;
%"TAP"
"6","(-3200,3000)","0","mstr_standard","I164";
;
CDS_LIB"mstr_standard"
BODY_TYPE"PLUMBING"
HDL_TAP"TRUE";
"B \NAC \NWC"5;
"S \NAC"
BN"3"152;
%"TAP"
"6","(-3200,2950)","0","mstr_standard","I165";
;
CDS_LIB"mstr_standard"
BODY_TYPE"PLUMBING"
HDL_TAP"TRUE";
"B \NAC \NWC"5;
"S \NAC"
BN"2"144;
%"TAP"
"6","(-3200,2850)","0","mstr_standard","I166";
;
CDS_LIB"mstr_standard"
BODY_TYPE"PLUMBING"
HDL_TAP"TRUE";
"B \NAC \NWC"7;
"S \NAC"
BN"3"145;
%"TAP"
"6","(-3200,2800)","0","mstr_standard","I167";
;
CDS_LIB"mstr_standard"
BODY_TYPE"PLUMBING"
HDL_TAP"TRUE";
"B \NAC \NWC"7;
"S \NAC"
BN"2"146;
%"SCONN288_H44441003"
"4","(-300,2000)","0","mstr_sconn","I168";
;
CDS_SEC"4"
PART_NUMBER"H44441-003"
BOM_SS"NOPOP"
LOCATION"J9L1"
MATERIAL"SCONN"
PACK_TYPE"PIP"
SEC_TYPE"PIP"
CDS_LIB"mstr_sconn"
BOM_COST"MEM"
SEC"4"
CDS_LOCATION"J9L1"
ROOM"DDR4_CH_M";
"VDD<0>"
$PN"236"13;
"VDD<6>"
$PN"220"13;
"VDD<10>"
$PN"209"13;
"VDD<13>"
$PN"92"13;
"VDD<16>"
$PN"85"13;
"VDD<19>"
$PN"76"13;
"VDD<23>"
$PN"64"13;
"VDD<25>"
$PN"59"13;
"VTT<0>"
$PN"221"21;
"12V<1>"
$PN"1"19;
"12V<0>"
$PN"145"19;
"VDD<24>"
$PN"61"13;
"VDD<22>"
$PN"67"13;
"VDD<21>"
$PN"70"13;
"VDD<20>"
$PN"73"13;
"VDD<18>"
$PN"80"13;
"VDD<17>"
$PN"83"13;
"VDD<15>"
$PN"88"13;
"VDD<14>"
$PN"90"13;
"VDD<12>"
$PN"204"13;
"VDD<11>"
$PN"206"13;
"VDD<9>"
$PN"212"13;
"VDD<8>"
$PN"215"13;
"VDD<7>"
$PN"217"13;
"VDD<5>"
$PN"223"13;
"VDD<4>"
$PN"226"13;
"VDD<3>"
$PN"229"13;
"VDD<2>"
$PN"231"13;
"VDD<1>"
$PN"233"13;
"VPP<4>"
$PN"142"18;
"VPP<3>"
$PN"143"18;
"VPP<2>"
$PN"288"18;
"VPP<1>"
$PN"286"18;
"VPP<0>"
$PN"287"18;
"VTT<1>"
$PN"77"21;
%"GND"
"1","(2500,1100)","2","mstr_symbols","I169";
;
VOLTAGE"0"
CDS_LIB"mstr_symbols"
SIZE"1B"
BOM_COST"MEM"
BODY_TYPE"PLUMBING"
ROOM"DDR4_CH_D"
HDL_POWER"GND";
"A\NAC"14;
%"TAP"
"6","(900,4000)","2","mstr_standard","I17";
;
CDS_LIB"mstr_standard"
BODY_TYPE"PLUMBING"
HDL_TAP"TRUE";
"B \NAC \NWC"12;
"S \NAC"
BN"6"55;
%"GND"
"1","(-5200,1725)","2","mstr_symbols","I175";
;
VOLTAGE"0"
BOM_COST"MEM"
CDS_LIB"mstr_symbols"
SIZE"1B"
BODY_TYPE"PLUMBING"
ROOM"DDR4_CH_D"
HDL_POWER"GND";
"A\NAC"15;
%"GND"
"1","(-4650,1150)","0","mstr_symbols","I176";
;
VOLTAGE"0"
SIZE"1B"
CDS_LIB"mstr_symbols"
BOM_COST"MEM"
BODY_TYPE"PLUMBING"
ROOM"DDR4_CH_D"
HDL_POWER"GND";
"A\NAC"16;
%"CAP_A"
"1","(-4650,1400)","2","dev_discrete","I177";
;
LOCATION"C9L1"
PART_NUMBER"A36096-045"
VALUE"0.01UF"
TOLERANCE"10%"
PACK_TYPE"0402V"
VOLTAGE"25V"
MATERIAL"X7R"
CDS_LOCATION"C9L1"
BOM_COST"MEM"
CDS_LIB"dev_discrete"
CDS_SEC"1"
SEC_TYPE"0402V"
SEC"1"
ROOM"DDR4_CH_M1";
"B"
$PN"2"16;
"A"
$PN"1"176;
%"PVPP_KLM"
"1","(-5200,2100)","0","mstr_symbols","I178";
;
VOLTAGE"2.5V"
BOM_COST"MEM"
CDS_LIB"mstr_symbols"
BODY_TYPE"PLUMBING"
ROOM"DDR4_CH_D"
HDL_POWER"PVPP_KLM";
"G\NAC"17;
%"PVPP_KLM"
"1","(-1000,3025)","0","mstr_symbols","I179";
;
VOLTAGE"2.5V"
BOM_COST"MEM"
CDS_LIB"mstr_symbols"
BODY_TYPE"PLUMBING"
ROOM"DDR4_CH_D"
HDL_POWER"PVPP_KLM";
"G\NAC"18;
%"TAP"
"6","(900,3900)","2","mstr_standard","I18";
;
CDS_LIB"mstr_standard"
BODY_TYPE"PLUMBING"
HDL_TAP"TRUE";
"B \NAC \NWC"12;
"S \NAC"
BN"5"57;
%"TAP"
"6","(-3650,3550)","0","mstr_standard","I184";
;
CDS_LIB"mstr_standard"
BODY_TYPE"PLUMBING"
HDL_TAP"TRUE";
"B \NAC \NWC"8;
"S \NAC"
BN"3"140;
%"TAP"
"6","(-3800,3500)","0","mstr_standard","I185";
;
CDS_LIB"mstr_standard"
BODY_TYPE"PLUMBING"
HDL_TAP"TRUE";
"B \NAC \NWC"9;
"S \NAC"
BN"3"139;
%"P12V_NVDIMM_KLM"
"1","(400,3000)","0","mstr_symbols","I186";
;
VOLTAGE"12.0"
CDS_LIB"mstr_symbols"
BODY_TYPE"PLUMBING"
HDL_POWER"P12V_NVDIMM_KLM";
"G\NAC"19;
%"TAP"
"6","(900,3800)","2","mstr_standard","I19";
;
CDS_LIB"mstr_standard"
BODY_TYPE"PLUMBING"
HDL_TAP"TRUE";
"B \NAC \NWC"12;
"S \NAC"
BN"4"59;
%"TAP"
"6","(900,3700)","2","mstr_standard","I20";
;
CDS_LIB"mstr_standard"
BODY_TYPE"PLUMBING"
HDL_TAP"TRUE";
"B \NAC \NWC"12;
"S \NAC"
BN"3"61;
%"TAP"
"6","(900,3500)","2","mstr_standard","I21";
;
CDS_LIB"mstr_standard"
BODY_TYPE"PLUMBING"
HDL_TAP"TRUE";
"B \NAC \NWC"12;
"S \NAC"
BN"1"22;
%"TAP"
"6","(900,3600)","2","mstr_standard","I22";
;
CDS_LIB"mstr_standard"
BODY_TYPE"PLUMBING"
HDL_TAP"TRUE";
"B \NAC \NWC"12;
"S \NAC"
BN"2"63;
%"TAP"
"6","(900,3400)","2","mstr_standard","I23";
;
CDS_LIB"mstr_standard"
BODY_TYPE"PLUMBING"
HDL_TAP"TRUE";
"B \NAC \NWC"12;
"S \NAC"
BN"0"24;
%"SCONN288_H44441003"
"3","(1800,2400)","0","mstr_sconn","I25";
;
CDS_SEC"3"
PART_NUMBER"H44441-003"
MATERIAL"SCONN"
LOCATION"J9L1"
BOM_SS"NOPOP"
PACK_TYPE"PIP"
SEC_TYPE"PIP"
CDS_LIB"mstr_sconn"
BOM_COST"DDR4_CH_M"
SEC"3"
CDS_LOCATION"J9L1"
ROOM"DDR4_CH_M";
"VSS<46>"
$PN"147"14;
"VSS<45>"
$PN"149"14;
"VSS<87>"
$PN"15"20;
"VSS<86>"
$PN"17"20;
"VSS<85>"
$PN"20"20;
"VSS<84>"
$PN"22"20;
"VSS<83>"
$PN"24"20;
"VSS<82>"
$PN"26"20;
"VSS<81>"
$PN"28"20;
"VSS<80>"
$PN"31"20;
"VSS<79>"
$PN"33"20;
"VSS<78>"
$PN"35"20;
"VSS<77>"
$PN"37"20;
"VSS<76>"
$PN"39"20;
"VSS<75>"
$PN"42"20;
"VSS<74>"
$PN"44"20;
"VSS<73>"
$PN"46"20;
"VSS<72>"
$PN"48"20;
"VSS<71>"
$PN"50"20;
"VSS<70>"
$PN"53"20;
"VSS<69>"
$PN"55"20;
"VSS<68>"
$PN"57"20;
"VSS<67>"
$PN"94"20;
"VSS<66>"
$PN"96"20;
"VSS<65>"
$PN"98"20;
"VSS<64>"
$PN"101"20;
"VSS<63>"
$PN"103"20;
"VSS<62>"
$PN"105"20;
"VSS<61>"
$PN"107"20;
"VSS<60>"
$PN"109"20;
"VSS<59>"
$PN"112"20;
"VSS<58>"
$PN"114"20;
"VSS<57>"
$PN"116"20;
"VSS<56>"
$PN"118"20;
"VSS<55>"
$PN"120"20;
"VSS<54>"
$PN"123"20;
"VSS<53>"
$PN"125"20;
"VSS<52>"
$PN"127"20;
"VSS<51>"
$PN"129"20;
"VSS<50>"
$PN"131"20;
"VSS<49>"
$PN"134"20;
"VSS<48>"
$PN"136"20;
"VSS<47>"
$PN"138"20;
"VSS<44>"
$PN"151"14;
"VSS<43>"
$PN"154"14;
"VSS<42>"
$PN"156"14;
"VSS<41>"
$PN"158"14;
"VSS<40>"
$PN"160"14;
"VSS<39>"
$PN"162"14;
"VSS<38>"
$PN"165"14;
"VSS<37>"
$PN"167"14;
"VSS<36>"
$PN"169"14;
"VSS<35>"
$PN"171"14;
"VSS<34>"
$PN"173"14;
"VSS<33>"
$PN"176"14;
"VSS<32>"
$PN"178"14;
"VSS<31>"
$PN"180"14;
"VSS<30>"
$PN"182"14;
"VSS<29>"
$PN"184"14;
"VSS<28>"
$PN"187"14;
"VSS<27>"
$PN"189"14;
"VSS<26>"
$PN"191"14;
"VSS<25>"
$PN"193"14;
"VSS<24>"
$PN"195"14;
"VSS<23>"
$PN"198"14;
"VSS<22>"
$PN"200"14;
"VSS<21>"
$PN"202"14;
"VSS<20>"
$PN"239"14;
"VSS<19>"
$PN"241"14;
"VSS<18>"
$PN"243"14;
"VSS<17>"
$PN"246"14;
"VSS<16>"
$PN"248"14;
"VSS<15>"
$PN"250"14;
"VSS<14>"
$PN"252"14;
"VSS<13>"
$PN"254"14;
"VSS<12>"
$PN"257"14;
"VSS<11>"
$PN"259"14;
"VSS<10>"
$PN"261"14;
"VSS<9>"
$PN"263"14;
"VSS<8>"
$PN"265"14;
"VSS<7>"
$PN"268"14;
"VSS<6>"
$PN"270"14;
"VSS<5>"
$PN"272"14;
"VSS<4>"
$PN"274"14;
"VSS<3>"
$PN"276"14;
"VSS<2>"
$PN"279"14;
"VSS<1>"
$PN"281"14;
"VSS<0>"
$PN"283"14;
"VSS<88>"
$PN"13"20;
"VSS<89>"
$PN"11"20;
"VSS<90>"
$PN"9"20;
"VSS<91>"
$PN"6"20;
"VSS<92>"
$PN"4"20;
"VSS<93>"
$PN"2"20;
%"GND"
"1","(1100,1100)","2","mstr_symbols","I26";
;
VOLTAGE"4V"
SIZE"1B"
CDS_LIB"mstr_symbols"
BOM_COST"PROC"
BODY_TYPE"PLUMBING"
ROOM"PROC"
HDL_POWER"GND";
"A\NAC"20;
%"TAP"
"6","(700,5150)","2","mstr_standard","I27";
;
CDS_LIB"mstr_standard"
BODY_TYPE"PLUMBING"
HDL_TAP"TRUE";
"B \NAC \NWC"11;
"S \NAC"
BN"17"32;
%"TAP"
"6","(700,5050)","2","mstr_standard","I28";
;
CDS_LIB"mstr_standard"
BODY_TYPE"PLUMBING"
HDL_TAP"TRUE";
"B \NAC \NWC"11;
"S \NAC"
BN"16"40;
%"TAP"
"6","(700,4750)","2","mstr_standard","I29";
;
CDS_LIB"mstr_standard"
BODY_TYPE"PLUMBING"
HDL_TAP"TRUE";
"B \NAC \NWC"11;
"S \NAC"
BN"13"46;
%"TAP"
"6","(900,5100)","2","mstr_standard","I3";
;
CDS_LIB"mstr_standard"
BODY_TYPE"PLUMBING"
HDL_TAP"TRUE";
"B \NAC \NWC"12;
"S \NAC"
BN"17"39;
%"TAP"
"6","(700,4650)","2","mstr_standard","I30";
;
CDS_LIB"mstr_standard"
BODY_TYPE"PLUMBING"
HDL_TAP"TRUE";
"B \NAC \NWC"11;
"S \NAC"
BN"12"48;
%"TAP"
"6","(700,4550)","2","mstr_standard","I31";
;
CDS_LIB"mstr_standard"
BODY_TYPE"PLUMBING"
HDL_TAP"TRUE";
"B \NAC \NWC"11;
"S \NAC"
BN"11"50;
%"TAP"
"6","(700,4950)","2","mstr_standard","I32";
;
CDS_LIB"mstr_standard"
BODY_TYPE"PLUMBING"
HDL_TAP"TRUE";
"B \NAC \NWC"11;
"S \NAC"
BN"15"42;
%"TAP"
"6","(700,4850)","2","mstr_standard","I33";
;
CDS_LIB"mstr_standard"
BODY_TYPE"PLUMBING"
HDL_TAP"TRUE";
"B \NAC \NWC"11;
"S \NAC"
BN"14"44;
%"TAP"
"6","(-1700,4550)","2","mstr_standard","I35";
;
CDS_LIB"mstr_standard"
BODY_TYPE"PLUMBING"
HDL_TAP"TRUE";
"B \NAC \NWC"10;
"S \NAC"
BN"59"74;
%"TAP"
"6","(-1700,4750)","2","mstr_standard","I36";
;
CDS_LIB"mstr_standard"
BODY_TYPE"PLUMBING"
HDL_TAP"TRUE";
"B \NAC \NWC"10;
"S \NAC"
BN"63"65;
%"TAP"
"6","(-1700,4700)","2","mstr_standard","I37";
;
CDS_LIB"mstr_standard"
BODY_TYPE"PLUMBING"
HDL_TAP"TRUE";
"B \NAC \NWC"10;
"S \NAC"
BN"62"67;
%"TAP"
"6","(-1700,4650)","2","mstr_standard","I38";
;
CDS_LIB"mstr_standard"
BODY_TYPE"PLUMBING"
HDL_TAP"TRUE";
"B \NAC \NWC"10;
"S \NAC"
BN"61"66;
%"TAP"
"6","(-1700,4600)","2","mstr_standard","I39";
;
CDS_LIB"mstr_standard"
BODY_TYPE"PLUMBING"
HDL_TAP"TRUE";
"B \NAC \NWC"10;
"S \NAC"
BN"60"68;
%"TAP"
"6","(900,5000)","2","mstr_standard","I4";
;
CDS_LIB"mstr_standard"
BODY_TYPE"PLUMBING"
HDL_TAP"TRUE";
"B \NAC \NWC"12;
"S \NAC"
BN"16"41;
%"TAP"
"6","(-1700,4300)","2","mstr_standard","I40";
;
CDS_LIB"mstr_standard"
BODY_TYPE"PLUMBING"
HDL_TAP"TRUE";
"B \NAC \NWC"10;
"S \NAC"
BN"54"30;
%"TAP"
"6","(-1700,4450)","2","mstr_standard","I41";
;
CDS_LIB"mstr_standard"
BODY_TYPE"PLUMBING"
HDL_TAP"TRUE";
"B \NAC \NWC"10;
"S \NAC"
BN"57"70;
%"TAP"
"6","(-1700,4500)","2","mstr_standard","I42";
;
CDS_LIB"mstr_standard"
BODY_TYPE"PLUMBING"
HDL_TAP"TRUE";
"B \NAC \NWC"10;
"S \NAC"
BN"58"69;
%"TAP"
"6","(-1700,4350)","2","mstr_standard","I43";
;
CDS_LIB"mstr_standard"
BODY_TYPE"PLUMBING"
HDL_TAP"TRUE";
"B \NAC \NWC"10;
"S \NAC"
BN"55"25;
%"TAP"
"6","(-1700,4400)","2","mstr_standard","I44";
;
CDS_LIB"mstr_standard"
BODY_TYPE"PLUMBING"
HDL_TAP"TRUE";
"B \NAC \NWC"10;
"S \NAC"
BN"56"26;
%"TAP"
"6","(-1700,4050)","2","mstr_standard","I45";
;
CDS_LIB"mstr_standard"
BODY_TYPE"PLUMBING"
HDL_TAP"TRUE";
"B \NAC \NWC"10;
"S \NAC"
BN"49"90;
%"TAP"
"6","(-1700,4250)","2","mstr_standard","I46";
;
CDS_LIB"mstr_standard"
BODY_TYPE"PLUMBING"
HDL_TAP"TRUE";
"B \NAC \NWC"10;
"S \NAC"
BN"53"31;
%"TAP"
"6","(-1700,4200)","2","mstr_standard","I47";
;
CDS_LIB"mstr_standard"
BODY_TYPE"PLUMBING"
HDL_TAP"TRUE";
"B \NAC \NWC"10;
"S \NAC"
BN"52"73;
%"TAP"
"6","(-1700,4100)","2","mstr_standard","I48";
;
CDS_LIB"mstr_standard"
BODY_TYPE"PLUMBING"
HDL_TAP"TRUE";
"B \NAC \NWC"10;
"S \NAC"
BN"50"71;
%"TAP"
"6","(-1700,4150)","2","mstr_standard","I49";
;
CDS_LIB"mstr_standard"
BODY_TYPE"PLUMBING"
HDL_TAP"TRUE";
"B \NAC \NWC"10;
"S \NAC"
BN"51"72;
%"TAP"
"6","(900,4900)","2","mstr_standard","I5";
;
CDS_LIB"mstr_standard"
BODY_TYPE"PLUMBING"
HDL_TAP"TRUE";
"B \NAC \NWC"12;
"S \NAC"
BN"15"43;
%"TAP"
"6","(-1700,3950)","2","mstr_standard","I50";
;
CDS_LIB"mstr_standard"
BODY_TYPE"PLUMBING"
HDL_TAP"TRUE";
"B \NAC \NWC"10;
"S \NAC"
BN"47"88;
%"TAP"
"6","(-1700,4000)","2","mstr_standard","I51";
;
CDS_LIB"mstr_standard"
BODY_TYPE"PLUMBING"
HDL_TAP"TRUE";
"B \NAC \NWC"10;
"S \NAC"
BN"48"89;
%"TAP"
"6","(-1700,3900)","2","mstr_standard","I52";
;
CDS_LIB"mstr_standard"
BODY_TYPE"PLUMBING"
HDL_TAP"TRUE";
"B \NAC \NWC"10;
"S \NAC"
BN"46"96;
%"TAP"
"6","(-1700,3800)","2","mstr_standard","I53";
;
CDS_LIB"mstr_standard"
BODY_TYPE"PLUMBING"
HDL_TAP"TRUE";
"B \NAC \NWC"10;
"S \NAC"
BN"44"95;
%"TAP"
"6","(-1700,3850)","2","mstr_standard","I54";
;
CDS_LIB"mstr_standard"
BODY_TYPE"PLUMBING"
HDL_TAP"TRUE";
"B \NAC \NWC"10;
"S \NAC"
BN"45"28;
%"TAP"
"6","(700,4250)","2","mstr_standard","I55";
;
CDS_LIB"mstr_standard"
BODY_TYPE"PLUMBING"
HDL_TAP"TRUE";
"B \NAC \NWC"11;
"S \NAC"
BN"8"35;
%"TAP"
"6","(700,4150)","2","mstr_standard","I56";
;
CDS_LIB"mstr_standard"
BODY_TYPE"PLUMBING"
HDL_TAP"TRUE";
"B \NAC \NWC"11;
"S \NAC"
BN"7"37;
%"TAP"
"6","(700,4050)","2","mstr_standard","I57";
;
CDS_LIB"mstr_standard"
BODY_TYPE"PLUMBING"
HDL_TAP"TRUE";
"B \NAC \NWC"11;
"S \NAC"
BN"6"54;
%"TAP"
"6","(700,4350)","2","mstr_standard","I58";
;
CDS_LIB"mstr_standard"
BODY_TYPE"PLUMBING"
HDL_TAP"TRUE";
"B \NAC \NWC"11;
"S \NAC"
BN"9"33;
%"TAP"
"6","(700,4450)","2","mstr_standard","I59";
;
CDS_LIB"mstr_standard"
BODY_TYPE"PLUMBING"
HDL_TAP"TRUE";
"B \NAC \NWC"11;
"S \NAC"
BN"10"52;
%"TAP"
"6","(900,4800)","2","mstr_standard","I6";
;
CDS_LIB"mstr_standard"
BODY_TYPE"PLUMBING"
HDL_TAP"TRUE";
"B \NAC \NWC"12;
"S \NAC"
BN"14"45;
%"TAP"
"6","(700,3750)","2","mstr_standard","I60";
;
CDS_LIB"mstr_standard"
BODY_TYPE"PLUMBING"
HDL_TAP"TRUE";
"B \NAC \NWC"11;
"S \NAC"
BN"3"60;
%"TAP"
"6","(700,3550)","2","mstr_standard","I61";
;
CDS_LIB"mstr_standard"
BODY_TYPE"PLUMBING"
HDL_TAP"TRUE";
"B \NAC \NWC"11;
"S \NAC"
BN"1"64;
%"TAP"
"6","(700,3650)","2","mstr_standard","I62";
;
CDS_LIB"mstr_standard"
BODY_TYPE"PLUMBING"
HDL_TAP"TRUE";
"B \NAC \NWC"11;
"S \NAC"
BN"2"62;
%"TAP"
"6","(700,3950)","2","mstr_standard","I63";
;
CDS_LIB"mstr_standard"
BODY_TYPE"PLUMBING"
HDL_TAP"TRUE";
"B \NAC \NWC"11;
"S \NAC"
BN"5"56;
%"TAP"
"6","(700,3850)","2","mstr_standard","I64";
;
CDS_LIB"mstr_standard"
BODY_TYPE"PLUMBING"
HDL_TAP"TRUE";
"B \NAC \NWC"11;
"S \NAC"
BN"4"58;
%"TAP"
"6","(700,3450)","2","mstr_standard","I65";
;
CDS_LIB"mstr_standard"
BODY_TYPE"PLUMBING"
HDL_TAP"TRUE";
"B \NAC \NWC"11;
"S \NAC"
BN"0"23;
%"TAP"
"6","(-1700,3750)","2","mstr_standard","I66";
;
CDS_LIB"mstr_standard"
BODY_TYPE"PLUMBING"
HDL_TAP"TRUE";
"B \NAC \NWC"10;
"S \NAC"
BN"43"94;
%"TAP"
"6","(-1700,3700)","2","mstr_standard","I67";
;
CDS_LIB"mstr_standard"
BODY_TYPE"PLUMBING"
HDL_TAP"TRUE";
"B \NAC \NWC"10;
"S \NAC"
BN"42"93;
%"TAP"
"6","(-1700,3600)","2","mstr_standard","I68";
;
CDS_LIB"mstr_standard"
BODY_TYPE"PLUMBING"
HDL_TAP"TRUE";
"B \NAC \NWC"10;
"S \NAC"
BN"40"91;
%"TAP"
"6","(-1700,3650)","2","mstr_standard","I69";
;
CDS_LIB"mstr_standard"
BODY_TYPE"PLUMBING"
HDL_TAP"TRUE";
"B \NAC \NWC"10;
"S \NAC"
BN"41"92;
%"TAP"
"6","(900,4700)","2","mstr_standard","I7";
;
CDS_LIB"mstr_standard"
BODY_TYPE"PLUMBING"
HDL_TAP"TRUE";
"B \NAC \NWC"12;
"S \NAC"
BN"13"47;
%"TAP"
"6","(-1700,3550)","2","mstr_standard","I70";
;
CDS_LIB"mstr_standard"
BODY_TYPE"PLUMBING"
HDL_TAP"TRUE";
"B \NAC \NWC"10;
"S \NAC"
BN"39"106;
%"TAP"
"6","(-1700,3500)","2","mstr_standard","I71";
;
CDS_LIB"mstr_standard"
BODY_TYPE"PLUMBING"
HDL_TAP"TRUE";
"B \NAC \NWC"10;
"S \NAC"
BN"38"98;
%"TAP"
"6","(-1700,3450)","2","mstr_standard","I72";
;
CDS_LIB"mstr_standard"
BODY_TYPE"PLUMBING"
HDL_TAP"TRUE";
"B \NAC \NWC"10;
"S \NAC"
BN"37"105;
%"TAP"
"6","(-1700,3400)","2","mstr_standard","I73";
;
CDS_LIB"mstr_standard"
BODY_TYPE"PLUMBING"
HDL_TAP"TRUE";
"B \NAC \NWC"10;
"S \NAC"
BN"36"99;
%"TAP"
"6","(-1700,3350)","2","mstr_standard","I74";
;
CDS_LIB"mstr_standard"
BODY_TYPE"PLUMBING"
HDL_TAP"TRUE";
"B \NAC \NWC"10;
"S \NAC"
BN"35"100;
%"TAP"
"6","(-1700,3300)","2","mstr_standard","I75";
;
CDS_LIB"mstr_standard"
BODY_TYPE"PLUMBING"
HDL_TAP"TRUE";
"B \NAC \NWC"10;
"S \NAC"
BN"34"104;
%"TAP"
"6","(-1700,3250)","2","mstr_standard","I76";
;
CDS_LIB"mstr_standard"
BODY_TYPE"PLUMBING"
HDL_TAP"TRUE";
"B \NAC \NWC"10;
"S \NAC"
BN"33"103;
%"TAP"
"6","(-1700,3200)","2","mstr_standard","I77";
;
CDS_LIB"mstr_standard"
BODY_TYPE"PLUMBING"
HDL_TAP"TRUE";
"B \NAC \NWC"10;
"S \NAC"
BN"32"102;
%"TAP"
"6","(-1700,3050)","2","mstr_standard","I78";
;
CDS_LIB"mstr_standard"
BODY_TYPE"PLUMBING"
HDL_TAP"TRUE";
"B \NAC \NWC"10;
"S \NAC"
BN"29"116;
%"TAP"
"6","(-1700,3100)","2","mstr_standard","I79";
;
CDS_LIB"mstr_standard"
BODY_TYPE"PLUMBING"
HDL_TAP"TRUE";
"B \NAC \NWC"10;
"S \NAC"
BN"30"97;
%"TAP"
"6","(900,4600)","2","mstr_standard","I8";
;
CDS_LIB"mstr_standard"
BODY_TYPE"PLUMBING"
HDL_TAP"TRUE";
"B \NAC \NWC"12;
"S \NAC"
BN"12"49;
%"TAP"
"6","(-1700,3150)","2","mstr_standard","I80";
;
CDS_LIB"mstr_standard"
BODY_TYPE"PLUMBING"
HDL_TAP"TRUE";
"B \NAC \NWC"10;
"S \NAC"
BN"31"101;
%"TAP"
"6","(-1700,2750)","2","mstr_standard","I81";
;
CDS_LIB"mstr_standard"
BODY_TYPE"PLUMBING"
HDL_TAP"TRUE";
"B \NAC \NWC"10;
"S \NAC"
BN"23"112;
%"TAP"
"6","(-1700,2950)","2","mstr_standard","I82";
;
CDS_LIB"mstr_standard"
BODY_TYPE"PLUMBING"
HDL_TAP"TRUE";
"B \NAC \NWC"10;
"S \NAC"
BN"27"109;
%"TAP"
"6","(-1700,3000)","2","mstr_standard","I83";
;
CDS_LIB"mstr_standard"
BODY_TYPE"PLUMBING"
HDL_TAP"TRUE";
"B \NAC \NWC"10;
"S \NAC"
BN"28"115;
%"TAP"
"6","(-1700,2900)","2","mstr_standard","I84";
;
CDS_LIB"mstr_standard"
BODY_TYPE"PLUMBING"
HDL_TAP"TRUE";
"B \NAC \NWC"10;
"S \NAC"
BN"26"108;
%"TAP"
"6","(-1700,2850)","2","mstr_standard","I85";
;
CDS_LIB"mstr_standard"
BODY_TYPE"PLUMBING"
HDL_TAP"TRUE";
"B \NAC \NWC"10;
"S \NAC"
BN"25"114;
%"TAP"
"6","(-1700,2800)","2","mstr_standard","I86";
;
CDS_LIB"mstr_standard"
BODY_TYPE"PLUMBING"
HDL_TAP"TRUE";
"B \NAC \NWC"10;
"S \NAC"
BN"24"113;
%"SCONN288_H44441003"
"2","(0,4300)","0","mstr_sconn","I87";
;
CDS_SEC"2"
LOCATION"J9L1"
PART_NUMBER"H44441-003"
MATERIAL"SCONN"
BOM_SS"NOPOP"
PACK_TYPE"PIP"
SEC_TYPE"PIP"
CDS_LIB"mstr_sconn"
BOM_COST"DDR4_CH_M"
SEC"2"
CDS_LOCATION"J9L1"
ROOM"DDR4_CH_M";
"DQS0N"
$PN"152"24;
"DQS0P"
$PN"153"23;
"DQS10N"
$PN"19"53;
"DQS10P"
$PN"18"52;
"DQS11N"
$PN"30"51;
"DQS11P"
$PN"29"50;
"DQS12N"
$PN"41"49;
"DQS12P"
$PN"40"48;
"DQS13N"
$PN"100"47;
"DQS13P"
$PN"99"46;
"DQS14N"
$PN"111"45;
"DQS14P"
$PN"110"44;
"DQS15N"
$PN"122"43;
"DQS15P"
$PN"121"42;
"DQS16N"
$PN"133"41;
"DQS16P"
$PN"132"40;
"DQS17N"
$PN"52"39;
"DQS17P"
$PN"51"32;
"DQS1N"
$PN"163"22;
"DQS1P"
$PN"164"64;
"DQS2N"
$PN"174"63;
"DQS2P"
$PN"175"62;
"DQS3N"
$PN"185"61;
"DQS3P"
$PN"186"60;
"DQS4N"
$PN"244"59;
"DQS4P"
$PN"245"58;
"DQS5N"
$PN"255"57;
"DQS5P"
$PN"256"56;
"DQS6N"
$PN"266"55;
"DQS6P"
$PN"267"54;
"DQS7N"
$PN"277"38;
"DQS7P"
$PN"278"37;
"DQS8N"
$PN"196"36;
"DQS8P"
$PN"197"35;
"DQS9N"
$PN"8"34;
"DQS9P"
$PN"7"33;
%"TAP"
"6","(-1700,2500)","2","mstr_standard","I88";
;
CDS_LIB"mstr_standard"
BODY_TYPE"PLUMBING"
HDL_TAP"TRUE";
"B \NAC \NWC"10;
"S \NAC"
BN"18"126;
%"TAP"
"6","(-1700,2700)","2","mstr_standard","I89";
;
CDS_LIB"mstr_standard"
BODY_TYPE"PLUMBING"
HDL_TAP"TRUE";
"B \NAC \NWC"10;
"S \NAC"
BN"22"107;
%"PVTT_KLM"
"1","(-1150,2700)","0","mstr_symbols","I9";
;
VOLTAGE"0.6V"
BOM_COST"PROC"
CDS_LIB"mstr_symbols"
BODY_TYPE"PLUMBING"
ROOM"PROC"
HDL_POWER"PVTT_KLM";
"G\NAC"21;
%"TAP"
"6","(-1700,2650)","2","mstr_standard","I90";
;
CDS_LIB"mstr_standard"
BODY_TYPE"PLUMBING"
HDL_TAP"TRUE";
"B \NAC \NWC"10;
"S \NAC"
BN"21"111;
%"TAP"
"6","(-1700,2550)","2","mstr_standard","I91";
;
CDS_LIB"mstr_standard"
BODY_TYPE"PLUMBING"
HDL_TAP"TRUE";
"B \NAC \NWC"10;
"S \NAC"
BN"19"127;
%"TAP"
"6","(-1700,2600)","2","mstr_standard","I92";
;
CDS_LIB"mstr_standard"
BODY_TYPE"PLUMBING"
HDL_TAP"TRUE";
"B \NAC \NWC"10;
"S \NAC"
BN"20"110;
%"TAP"
"6","(-1700,2250)","2","mstr_standard","I93";
;
CDS_LIB"mstr_standard"
BODY_TYPE"PLUMBING"
HDL_TAP"TRUE";
"B \NAC \NWC"10;
"S \NAC"
BN"13"125;
%"TAP"
"6","(-1700,2400)","2","mstr_standard","I94";
;
CDS_LIB"mstr_standard"
BODY_TYPE"PLUMBING"
HDL_TAP"TRUE";
"B \NAC \NWC"10;
"S \NAC"
BN"16"117;
%"TAP"
"6","(-1700,2450)","2","mstr_standard","I95";
;
CDS_LIB"mstr_standard"
BODY_TYPE"PLUMBING"
HDL_TAP"TRUE";
"B \NAC \NWC"10;
"S \NAC"
BN"17"123;
%"TAP"
"6","(-1700,2300)","2","mstr_standard","I96";
;
CDS_LIB"mstr_standard"
BODY_TYPE"PLUMBING"
HDL_TAP"TRUE";
"B \NAC \NWC"10;
"S \NAC"
BN"14"119;
%"TAP"
"6","(-1700,2350)","2","mstr_standard","I97";
;
CDS_LIB"mstr_standard"
BODY_TYPE"PLUMBING"
HDL_TAP"TRUE";
"B \NAC \NWC"10;
"S \NAC"
BN"15"118;
%"TAP"
"6","(-1700,2000)","2","mstr_standard","I98";
;
CDS_LIB"mstr_standard"
BODY_TYPE"PLUMBING"
HDL_TAP"TRUE";
"B \NAC \NWC"10;
"S \NAC"
BN"8"128;
%"TAP"
"6","(-1700,2100)","2","mstr_standard","I99";
;
CDS_LIB"mstr_standard"
BODY_TYPE"PLUMBING"
HDL_TAP"TRUE";
"B \NAC \NWC"10;
"S \NAC"
BN"10"122;
END.
